# T6G (Grand Teton) — schematic netlist excerpt (pin names and nets, part order shuffled) for the footprints in the layout excerpt that follows; sources: Cadence DE-HDL packaged netlist, KiCad conversion of 04192023_DAF0TMB3IC0_F0TG_MB_C_brd_V02_OCP.brd

C8021  Q_CAP  100NF 50V 10% EMPTY  pkg C0402  page 268 : A = P12V_AUX_UV_TRIGGER ; B = GND
R1084  Q_RES  0 5% CHIP  pkg 0201LF  page 299 : A = NCF_A1_CPU0_P2_GND ; B = GND
PR3964  Q_RES  7.15K 1% CHIP  pkg 0402LF  page 146 : A = P3V3_E1S_UV_0 ; B = P3V3_E1S_OV_0

(kicad_pcb
	(version 20260206)
	(generator "pcbnew")
	(generator_version "10.0")
	(general
		(thickness 1.6)
		(legacy_teardrops no)
	)
	(paper "A4")
	(title_block
		(title "04192023_DAF0TMB3IC0_F0TG_MB_C_brd_V02_OCP.brd")
		(comment 1 "Grand Teton / footprints 65-67 of 8354")
	)
	(layers
		(0 "F.Cu" signal "TOP")
		(4 "In1.Cu" signal "GND")
		(6 "In2.Cu" signal "IN1")
		(8 "In3.Cu" signal "GND1")
		(10 "In4.Cu" signal "IN2")
		(12 "In5.Cu" signal "GND2")
		(14 "In6.Cu" signal "IN3")
		(16 "In7.Cu" signal "GND3")
		(18 "In8.Cu" signal "VCC")
		(20 "In9.Cu" signal "VCC1")
		(22 "In10.Cu" signal "GND4")
		(24 "In11.Cu" signal "IN4")
		(26 "In12.Cu" signal "GND5")
		(28 "In13.Cu" signal "IN5")
		(30 "In14.Cu" signal "GND6")
		(32 "In15.Cu" signal "IN6")
		(34 "In16.Cu" signal "GND7")
		(2 "B.Cu" signal "BOTTOM")
		(9 "F.Adhes" user "F.Adhesive")
		(11 "B.Adhes" user "B.Adhesive")
		(13 "F.Paste" user "Package Geometry/Pastemask Top")
		(15 "B.Paste" user "Package Geometry/Pastemask Bottom")
		(5 "F.SilkS" user "Ref Des/Silkscreen Top")
		(7 "B.SilkS" user "Ref Des/Silkscreen Bottom")
		(1 "F.Mask" user "Board Geometry/Soldermask Top")
		(3 "B.Mask" user "Board Geometry/Soldermask Bottom")
		(17 "Dwgs.User" user "User.Drawings")
		(19 "Cmts.User" user "User.Comments")
		(21 "Eco1.User" user "User.Eco1")
		(23 "Eco2.User" user "User.Eco2")
		(25 "Edge.Cuts" user "Board Geometry/Outline")
		(27 "Margin" user)
		(31 "F.CrtYd" user "Package Geometry/Place Bound Top")
		(29 "B.CrtYd" user "Package Geometry/Place Bound Bottom")
		(35 "F.Fab" user "Ref Des/Assembly Top")
		(33 "B.Fab" user "Ref Des/Assembly Bottom")
	)
	(footprint ""
		(layer "F.Cu")
		(at 145.669 -118.364)
		(property "Reference" "C8021"
			(at 0 0 0)
			(layer "F.SilkS")
			(hide yes)
			(effects
				(font
					(size 1.27 1.27)
				)
			)
		)
		(property "Value" ""
			(at 0 0 0)
			(layer "F.Fab")
			(effects
				(font
					(size 1.27 1.27)
				)
			)
		)
		(duplicate_pad_numbers_are_jumpers no)
		(fp_line
			(start -0.7874 -0.4064)
			(end 0.7874 -0.4064)
			(stroke
				(width 0.1524)
				(type default)
			)
			(layer "F.SilkS")
		)
		(fp_line
			(start -0.7874 0.4064)
			(end -0.7874 -0.4064)
			(stroke
				(width 0.1524)
				(type default)
			)
			(layer "F.SilkS")
		)
		(fp_line
			(start 0.7874 -0.4064)
			(end 0.7874 0.4064)
			(stroke
				(width 0.1524)
				(type default)
			)
			(layer "F.SilkS")
		)
		(fp_line
			(start 0.7874 0.4064)
			(end -0.7874 0.4064)
			(stroke
				(width 0.1524)
				(type default)
			)
			(layer "F.SilkS")
		)
		(fp_line
			(start -0.67945 -0.305054)
			(end -0.12065 -0.305054)
			(stroke
				(width 0.1)
				(type default)
			)
			(layer "F.Fab")
		)
		(fp_line
			(start -0.67945 0.3048)
			(end -0.67945 -0.305054)
			(stroke
				(width 0.1)
				(type default)
			)
			(layer "F.Fab")
		)
		(fp_line
			(start -0.12065 -0.305054)
			(end -0.12065 -0.2794)
			(stroke
				(width 0.1)
				(type default)
			)
			(layer "F.Fab")
		)
		(fp_line
			(start -0.12065 -0.2794)
			(end 0.12065 -0.2794)
			(stroke
				(width 0.1)
				(type default)
			)
			(layer "F.Fab")
		)
		(fp_line
			(start -0.12065 0.2794)
			(end -0.12065 0.3048)
			(stroke
				(width 0.1)
				(type default)
			)
			(layer "F.Fab")
		)
		(fp_line
			(start -0.12065 0.3048)
			(end -0.67945 0.3048)
			(stroke
				(width 0.1)
				(type default)
			)
			(layer "F.Fab")
		)
		(fp_line
			(start 0.120396 0.2794)
			(end -0.12065 0.2794)
			(stroke
				(width 0.1)
				(type default)
			)
			(layer "F.Fab")
		)
		(fp_line
			(start 0.120396 0.3048)
			(end 0.120396 0.2794)
			(stroke
				(width 0.1)
				(type default)
			)
			(layer "F.Fab")
		)
		(fp_line
			(start 0.12065 -0.3048)
			(end 0.67945 -0.3048)
			(stroke
				(width 0.1)
				(type default)
			)
			(layer "F.Fab")
		)
		(fp_line
			(start 0.12065 -0.2794)
			(end 0.12065 -0.3048)
			(stroke
				(width 0.1)
				(type default)
			)
			(layer "F.Fab")
		)
		(fp_line
			(start 0.67945 -0.3048)
			(end 0.67945 0.3048)
			(stroke
				(width 0.1)
				(type default)
			)
			(layer "F.Fab")
		)
		(fp_line
			(start 0.67945 0.3048)
			(end 0.120396 0.3048)
			(stroke
				(width 0.1)
				(type default)
			)
			(layer "F.Fab")
		)
		(pad "1" smd circle
			(at -0.40005 0)
			(size 0 0)
			(layers "F.Cu" "F.Mask" "F.Paste")
			(net "P12V_AUX_UV_TRIGGER")
		)
		(pad "2" smd circle
			(at 0.40005 0)
			(size 0 0)
			(layers "F.Cu" "F.Mask" "F.Paste")
			(net "GND")
		)
	)
	(footprint ""
		(layer "F.Cu")
		(at 424.609006 -402.7424 -90)
		(property "Reference" "R1084"
			(at 0 0 270)
			(layer "F.SilkS")
			(hide yes)
			(effects
				(font
					(size 1.27 1.27)
				)
			)
		)
		(property "Value" ""
			(at 0 0 270)
			(layer "F.Fab")
			(effects
				(font
					(size 1.27 1.27)
				)
			)
		)
		(duplicate_pad_numbers_are_jumpers no)
		(fp_line
			(start -0.32512 0.175006)
			(end -0.32512 -0.175006)
			(stroke
				(width 0.1)
				(type default)
			)
			(layer "F.Fab")
		)
		(fp_line
			(start 0.32512 0.175006)
			(end -0.32512 0.175006)
			(stroke
				(width 0.1)
				(type default)
			)
			(layer "F.Fab")
		)
		(fp_line
			(start -0.32512 -0.175006)
			(end 0.32512 -0.175006)
			(stroke
				(width 0.1)
				(type default)
			)
			(layer "F.Fab")
		)
		(fp_line
			(start 0.32512 -0.175006)
			(end 0.32512 0.175006)
			(stroke
				(width 0.1)
				(type default)
			)
			(layer "F.Fab")
		)
		(pad "1" smd rect
			(at -0.2667 0 270)
			(size 0.3048 0.381)
			(layers "F.Cu" "F.Mask" "F.Paste")
			(net "NCF_A1_CPU0_P2_GND")
		)
		(pad "2" smd rect
			(at 0.2667 0 90)
			(size 0.3048 0.381)
			(layers "F.Cu" "F.Mask" "F.Paste")
			(net "GND")
		)
	)
	(footprint ""
		(layer "F.Cu")
		(at 219.276676 -67.954144 -90)
		(property "Reference" "PR3964"
			(at 0 0 270)
			(layer "F.SilkS")
			(hide yes)
			(effects
				(font
					(size 1.27 1.27)
				)
			)
		)
		(property "Value" ""
			(at 0 0 270)
			(layer "F.Fab")
			(effects
				(font
					(size 1.27 1.27)
				)
			)
		)
		(duplicate_pad_numbers_are_jumpers no)
		(fp_line
			(start -0.7874 0.4064)
			(end -0.7874 -0.4064)
			(stroke
				(width 0.1524)
				(type default)
			)
			(layer "F.SilkS")
		)
		(fp_line
			(start 0.7874 0.4064)
			(end -0.7874 0.4064)
			(stroke
				(width 0.1524)
				(type default)
			)
			(layer "F.SilkS")
		)
		(fp_line
			(start -0.7874 -0.4064)
			(end 0.7874 -0.4064)
			(stroke
				(width 0.1524)
				(type default)
			)
			(layer "F.SilkS")
		)
		(fp_line
			(start 0.7874 -0.4064)
			(end 0.7874 0.4064)
			(stroke
				(width 0.1524)
				(type default)
			)
			(layer "F.SilkS")
		)
		(fp_line
			(start -0.67945 0.3048)
			(end -0.67945 -0.305054)
			(stroke
				(width 0.1)
				(type default)
			)
			(layer "F.Fab")
		)
		(fp_line
			(start -0.12065 0.3048)
			(end -0.67945 0.3048)
			(stroke
				(width 0.1)
				(type default)
			)
			(layer "F.Fab")
		)
		(fp_line
			(start 0.120396 0.3048)
			(end 0.120396 0.2794)
			(stroke
				(width 0.1)
				(type default)
			)
			(layer "F.Fab")
		)
		(fp_line
			(start 0.67945 0.3048)
			(end 0.120396 0.3048)
			(stroke
				(width 0.1)
				(type default)
			)
			(layer "F.Fab")
		)
		(fp_line
			(start -0.12065 0.2794)
			(end -0.12065 0.3048)
			(stroke
				(width 0.1)
				(type default)
			)
			(layer "F.Fab")
		)
		(fp_line
			(start 0.120396 0.2794)
			(end -0.12065 0.2794)
			(stroke
				(width 0.1)
				(type default)
			)
			(layer "F.Fab")
		)
		(fp_line
			(start -0.12065 -0.2794)
			(end 0.12065 -0.2794)
			(stroke
				(width 0.1)
				(type default)
			)
			(layer "F.Fab")
		)
		(fp_line
			(start 0.12065 -0.2794)
			(end 0.12065 -0.3048)
			(stroke
				(width 0.1)
				(type default)
			)
			(layer "F.Fab")
		)
		(fp_line
			(start 0.12065 -0.3048)
			(end 0.67945 -0.3048)
			(stroke
				(width 0.1)
				(type default)
			)
			(layer "F.Fab")
		)
		(fp_line
			(start 0.67945 -0.3048)
			(end 0.67945 0.3048)
			(stroke
				(width 0.1)
				(type default)
			)
			(layer "F.Fab")
		)
		(fp_line
			(start -0.67945 -0.305054)
			(end -0.12065 -0.305054)
			(stroke
				(width 0.1)
				(type default)
			)
			(layer "F.Fab")
		)
		(fp_line
			(start -0.12065 -0.305054)
			(end -0.12065 -0.2794)
			(stroke
				(width 0.1)
				(type default)
			)
			(layer "F.Fab")
		)
		(pad "1" smd circle
			(at -0.40005 0 270)
			(size 0 0)
			(layers "F.Cu" "F.Mask" "F.Paste")
			(net "P3V3_E1S_UV_0")
		)
		(pad "2" smd circle
			(at 0.40005 0 270)
			(size 0 0)
			(layers "F.Cu" "F.Mask" "F.Paste")
			(net "P3V3_E1S_OV_0")
		)
	)
)
